(kicad_pcb
	(version 20260206)
	(generator "pcbnew")
	(generator_version "10.0")
	(general
		(thickness 1.6)
		(legacy_teardrops no)
	)
	(paper "A4")
	(title_block
		(title "01162023_DA0F0TEBIF0_F0T_Expander_BD_F_brd_V02_OCP.brd")
		(comment 1 "Grand Teton / footprint 5622 of 9728 (PEX2), pads 117-233 of 2397")
	)
	(layers
		(0 "F.Cu" signal "TOP")
		(4 "In1.Cu" signal "GND")
		(6 "In2.Cu" signal "VCC")
		(8 "In3.Cu" signal "VCC1")
		(10 "In4.Cu" signal "GND1")
		(12 "In5.Cu" signal "IN1")
		(14 "In6.Cu" signal "GND2")
		(16 "In7.Cu" signal "IN2")
		(18 "In8.Cu" signal "GND3")
		(20 "In9.Cu" signal "IN3")
		(22 "In10.Cu" signal "GND4")
		(24 "In11.Cu" signal "IN4")
		(26 "In12.Cu" signal "GND5")
		(28 "In13.Cu" signal "IN5")
		(30 "In14.Cu" signal "GND6")
		(32 "In15.Cu" signal "IN6")
		(34 "In16.Cu" signal "GND7")
		(2 "B.Cu" signal "BOTTOM")
		(9 "F.Adhes" user "F.Adhesive")
		(11 "B.Adhes" user "B.Adhesive")
		(13 "F.Paste" user "Package Geometry/Pastemask Top")
		(15 "B.Paste" user "Package Geometry/Pastemask Bottom")
		(5 "F.SilkS" user "Ref Des/Silkscreen Top")
		(7 "B.SilkS" user "Ref Des/Silkscreen Bottom")
		(1 "F.Mask" user "Board Geometry/Soldermask Top")
		(3 "B.Mask" user "Board Geometry/Soldermask Bottom")
		(17 "Dwgs.User" user "User.Drawings")
		(19 "Cmts.User" user "User.Comments")
		(21 "Eco1.User" user "User.Eco1")
		(23 "Eco2.User" user "User.Eco2")
		(25 "Edge.Cuts" user "Board Geometry/Outline")
		(27 "Margin" user)
		(31 "F.CrtYd" user "Package Geometry/Place Bound Top")
		(29 "B.CrtYd" user "Package Geometry/Place Bound Bottom")
		(35 "F.Fab" user "Ref Des/Assembly Top")
		(33 "B.Fab" user "Ref Des/Assembly Bottom")
	)
	(footprint ""
		(layer "F.Cu")
		(at 291.84981 -295.89984)
		(property "Reference" "PEX2"
			(at -3.35153 35.56762 0)
			(unlocked yes)
			(layer "F.SilkS")
			(effects
				(font
					(size 2.032 1.524)
					(thickness 0.1524)
				)
				(justify left)
			)
		)
		(property "Value" ""
			(at 0 0 0)
			(layer "F.Fab")
			(effects
				(font
					(size 1.27 1.27)
				)
			)
		)
		(duplicate_pad_numbers_are_jumpers no)
		(pad "AB21" smd circle
			(at -3.800094 -2.84988)
			(size 0.4572 0.4572)
			(layers "F.Cu" "F.Mask" "F.Paste")
			(net "P0V8_SERDES_VDDA_PEX2")
		)
		(pad "AB22" smd circle
			(at -2.84988 -2.84988)
			(size 0.4572 0.4572)
			(layers "F.Cu" "F.Mask" "F.Paste")
			(net "P0V8_SERDES_VDDA_PEX2")
		)
		(pad "AB23" smd circle
			(at -1.89992 -2.84988)
			(size 0.4572 0.4572)
			(layers "F.Cu" "F.Mask" "F.Paste")
			(net "P0V8_SERDES_VDDA_PEX2")
		)
		(pad "AB24" smd circle
			(at -0.94996 -2.84988)
			(size 0.4572 0.4572)
			(layers "F.Cu" "F.Mask" "F.Paste")
			(net "P0V8_SERDES_VDDA_PEX2")
		)
		(pad "AB25" smd circle
			(at 0 -2.84988)
			(size 0.4572 0.4572)
			(layers "F.Cu" "F.Mask" "F.Paste")
			(net "P0V8_SERDES_VDDA_PEX2")
		)
		(pad "AB26" smd circle
			(at 0.94996 -2.84988)
			(size 0.4572 0.4572)
			(layers "F.Cu" "F.Mask" "F.Paste")
			(net "P0V8_SERDES_VDDA_PEX2")
		)
		(pad "AB27" smd circle
			(at 1.89992 -2.84988)
			(size 0.4572 0.4572)
			(layers "F.Cu" "F.Mask" "F.Paste")
			(net "P0V8_SERDES_VDDA_PEX2")
		)
		(pad "AB28" smd circle
			(at 2.84988 -2.84988)
			(size 0.4572 0.4572)
			(layers "F.Cu" "F.Mask" "F.Paste")
			(net "P0V8_SERDES_VDDA_PEX2")
		)
		(pad "AB29" smd circle
			(at 3.800094 -2.84988)
			(size 0.4572 0.4572)
			(layers "F.Cu" "F.Mask" "F.Paste")
			(net "P0V8_SERDES_VDDA_PEX2")
		)
		(pad "AB30" smd circle
			(at 4.750054 -2.84988)
			(size 0.4572 0.4572)
			(layers "F.Cu" "F.Mask" "F.Paste")
			(net "P0V8_SERDES_VDDA_PEX2")
		)
		(pad "AB31" smd circle
			(at 5.700014 -2.84988)
			(size 0.4572 0.4572)
			(layers "F.Cu" "F.Mask" "F.Paste")
			(net "P0V8_SERDES_VDDA_PEX2")
		)
		(pad "AB32" smd circle
			(at 6.649974 -2.84988)
			(size 0.4572 0.4572)
			(layers "F.Cu" "F.Mask" "F.Paste")
			(net "P0V8_SERDES_VDDA_PEX2")
		)
		(pad "AB33" smd circle
			(at 7.599934 -2.84988)
			(size 0.4572 0.4572)
			(layers "F.Cu" "F.Mask" "F.Paste")
			(net "P0V8_SERDES_VDDA_PEX2")
		)
		(pad "AB34" smd circle
			(at 8.549894 -2.84988)
			(size 0.4572 0.4572)
			(layers "F.Cu" "F.Mask" "F.Paste")
			(net "GND")
		)
		(pad "AB35" smd circle
			(at 9.500108 -2.84988)
			(size 0.4572 0.4572)
			(layers "F.Cu" "F.Mask" "F.Paste")
			(net "Net_524")
		)
		(pad "AB36" smd circle
			(at 10.450068 -2.84988)
			(size 0.4572 0.4572)
			(layers "F.Cu" "F.Mask" "F.Paste")
			(net "GND")
		)
		(pad "AB37" smd circle
			(at 11.400028 -2.84988)
			(size 0.4572 0.4572)
			(layers "F.Cu" "F.Mask" "F.Paste")
			(net "GND")
		)
		(pad "AB38" smd circle
			(at 12.349988 -2.84988)
			(size 0.4572 0.4572)
			(layers "F.Cu" "F.Mask" "F.Paste")
			(net "GND")
		)
		(pad "AB39" smd circle
			(at 13.299948 -2.84988)
			(size 0.4572 0.4572)
			(layers "F.Cu" "F.Mask" "F.Paste")
			(net "GND")
		)
		(pad "AB40" smd circle
			(at 14.249908 -2.84988)
			(size 0.4572 0.4572)
			(layers "F.Cu" "F.Mask" "F.Paste")
			(net "GND")
		)
		(pad "AB41" smd circle
			(at 15.200122 -2.84988)
			(size 0.4572 0.4572)
			(layers "F.Cu" "F.Mask" "F.Paste")
			(net "Net_1671")
		)
		(pad "AB42" smd circle
			(at 16.150082 -2.84988)
			(size 0.4572 0.4572)
			(layers "F.Cu" "F.Mask" "F.Paste")
			(net "Net_1696")
		)
		(pad "AB43" smd circle
			(at 17.100042 -2.84988)
			(size 0.4572 0.4572)
			(layers "F.Cu" "F.Mask" "F.Paste")
			(net "GND")
		)
		(pad "AB44" smd circle
			(at 18.050002 -2.84988)
			(size 0.4572 0.4572)
			(layers "F.Cu" "F.Mask" "F.Paste")
			(net "GND")
		)
		(pad "AB45" smd circle
			(at 18.999962 -2.84988)
			(size 0.4572 0.4572)
			(layers "F.Cu" "F.Mask" "F.Paste")
			(net "GND")
		)
		(pad "AB46" smd circle
			(at 19.949922 -2.84988)
			(size 0.4572 0.4572)
			(layers "F.Cu" "F.Mask" "F.Paste")
			(net "GND")
		)
		(pad "AB47" smd circle
			(at 20.899882 -2.84988)
			(size 0.4572 0.4572)
			(layers "F.Cu" "F.Mask" "F.Paste")
			(net "GND")
		)
		(pad "AB48" smd circle
			(at 21.850096 -2.84988)
			(size 0.4572 0.4572)
			(layers "F.Cu" "F.Mask" "F.Paste")
			(net "Net_1564")
		)
		(pad "AB49" smd circle
			(at 22.800056 -2.84988)
			(size 0.4572 0.4572)
			(layers "F.Cu" "F.Mask" "F.Paste")
			(net "Net_1636")
		)
		(pad "AC1" smd circle
			(at -22.800056 -1.89992)
			(size 0.4572 0.4572)
			(layers "F.Cu" "F.Mask" "F.Paste")
			(net "CLK_100M_DB2000QL_PEX2_S1_R_DN")
		)
		(pad "AC2" smd circle
			(at -21.850096 -1.89992)
			(size 0.4572 0.4572)
			(layers "F.Cu" "F.Mask" "F.Paste")
			(net "CLK_100M_DB2000QL_PEX2_S1_R_DP")
		)
		(pad "AC3" smd circle
			(at -20.899882 -1.89992)
			(size 0.4572 0.4572)
			(layers "F.Cu" "F.Mask" "F.Paste")
			(net "GND")
		)
		(pad "AC4" smd circle
			(at -19.949922 -1.89992)
			(size 0.4572 0.4572)
			(layers "F.Cu" "F.Mask" "F.Paste")
			(net "GND")
		)
		(pad "AC5" smd circle
			(at -18.999962 -1.89992)
			(size 0.4572 0.4572)
			(layers "F.Cu" "F.Mask" "F.Paste")
			(net "GND")
		)
		(pad "AC6" smd circle
			(at -18.050002 -1.89992)
			(size 0.4572 0.4572)
			(layers "F.Cu" "F.Mask" "F.Paste")
			(net "GND")
		)
		(pad "AC7" smd circle
			(at -17.100042 -1.89992)
			(size 0.4572 0.4572)
			(layers "F.Cu" "F.Mask" "F.Paste")
			(net "Net_5398")
		)
		(pad "AC8" smd circle
			(at -16.150082 -1.89992)
			(size 0.4572 0.4572)
			(layers "F.Cu" "F.Mask" "F.Paste")
			(net "Net_5400")
		)
		(pad "AC9" smd circle
			(at -15.200122 -1.89992)
			(size 0.4572 0.4572)
			(layers "F.Cu" "F.Mask" "F.Paste")
			(net "GND")
		)
		(pad "AC10" smd circle
			(at -14.249908 -1.89992)
			(size 0.4572 0.4572)
			(layers "F.Cu" "F.Mask" "F.Paste")
			(net "P1V8_VDDA_PEX2")
		)
		(pad "AC11" smd circle
			(at -13.299948 -1.89992)
			(size 0.4572 0.4572)
			(layers "F.Cu" "F.Mask" "F.Paste")
			(net "GND")
		)
		(pad "AC12" smd circle
			(at -12.349988 -1.89992)
			(size 0.4572 0.4572)
			(layers "F.Cu" "F.Mask" "F.Paste")
			(net "GND")
		)
		(pad "AC13" smd circle
			(at -11.400028 -1.89992)
			(size 0.4572 0.4572)
			(layers "F.Cu" "F.Mask" "F.Paste")
			(net "SYSPLL_VDDA18_PEX2")
		)
		(pad "AC14" smd circle
			(at -10.450068 -1.89992)
			(size 0.4572 0.4572)
			(layers "F.Cu" "F.Mask" "F.Paste")
			(net "GND")
		)
		(pad "AC15" smd circle
			(at -9.500108 -1.89992)
			(size 0.4572 0.4572)
			(layers "F.Cu" "F.Mask" "F.Paste")
			(net "P0V8_PEX2")
		)
		(pad "AC16" smd circle
			(at -8.549894 -1.89992)
			(size 0.4572 0.4572)
			(layers "F.Cu" "F.Mask" "F.Paste")
			(net "GND")
		)
		(pad "AC17" smd circle
			(at -7.599934 -1.89992)
			(size 0.4572 0.4572)
			(layers "F.Cu" "F.Mask" "F.Paste")
			(net "P0V8_PEX2")
		)
		(pad "AC18" smd circle
			(at -6.649974 -1.89992)
			(size 0.4572 0.4572)
			(layers "F.Cu" "F.Mask" "F.Paste")
			(net "GND")
		)
		(pad "AC19" smd circle
			(at -5.700014 -1.89992)
			(size 0.4572 0.4572)
			(layers "F.Cu" "F.Mask" "F.Paste")
			(net "P0V8_PEX2")
		)
		(pad "AC20" smd circle
			(at -4.750054 -1.89992)
			(size 0.4572 0.4572)
			(layers "F.Cu" "F.Mask" "F.Paste")
			(net "GND")
		)
		(pad "AC21" smd circle
			(at -3.800094 -1.89992)
			(size 0.4572 0.4572)
			(layers "F.Cu" "F.Mask" "F.Paste")
			(net "P0V8_PEX2")
		)
		(pad "AC22" smd circle
			(at -2.84988 -1.89992)
			(size 0.4572 0.4572)
			(layers "F.Cu" "F.Mask" "F.Paste")
			(net "GND")
		)
		(pad "AC23" smd circle
			(at -1.89992 -1.89992)
			(size 0.4572 0.4572)
			(layers "F.Cu" "F.Mask" "F.Paste")
			(net "P0V8_PEX2")
		)
		(pad "AC24" smd circle
			(at -0.94996 -1.89992)
			(size 0.4572 0.4572)
			(layers "F.Cu" "F.Mask" "F.Paste")
			(net "GND")
		)
		(pad "AC25" smd circle
			(at 0 -1.89992)
			(size 0.4572 0.4572)
			(layers "F.Cu" "F.Mask" "F.Paste")
			(net "P0V8_PEX2")
		)
		(pad "AC26" smd circle
			(at 0.94996 -1.89992)
			(size 0.4572 0.4572)
			(layers "F.Cu" "F.Mask" "F.Paste")
			(net "GND")
		)
		(pad "AC27" smd circle
			(at 1.89992 -1.89992)
			(size 0.4572 0.4572)
			(layers "F.Cu" "F.Mask" "F.Paste")
			(net "P0V8_PEX2")
		)
		(pad "AC28" smd circle
			(at 2.84988 -1.89992)
			(size 0.4572 0.4572)
			(layers "F.Cu" "F.Mask" "F.Paste")
			(net "GND")
		)
		(pad "AC29" smd circle
			(at 3.800094 -1.89992)
			(size 0.4572 0.4572)
			(layers "F.Cu" "F.Mask" "F.Paste")
			(net "P0V8_PEX2")
		)
		(pad "AC30" smd circle
			(at 4.750054 -1.89992)
			(size 0.4572 0.4572)
			(layers "F.Cu" "F.Mask" "F.Paste")
			(net "GND")
		)
		(pad "AC31" smd circle
			(at 5.700014 -1.89992)
			(size 0.4572 0.4572)
			(layers "F.Cu" "F.Mask" "F.Paste")
			(net "P0V8_PEX2")
		)
		(pad "AC32" smd circle
			(at 6.649974 -1.89992)
			(size 0.4572 0.4572)
			(layers "F.Cu" "F.Mask" "F.Paste")
			(net "GND")
		)
		(pad "AC33" smd circle
			(at 7.599934 -1.89992)
			(size 0.4572 0.4572)
			(layers "F.Cu" "F.Mask" "F.Paste")
			(net "P0V8_PEX2")
		)
		(pad "AC34" smd circle
			(at 8.549894 -1.89992)
			(size 0.4572 0.4572)
			(layers "F.Cu" "F.Mask" "F.Paste")
			(net "GND")
		)
		(pad "AC35" smd circle
			(at 9.500108 -1.89992)
			(size 0.4572 0.4572)
			(layers "F.Cu" "F.Mask" "F.Paste")
			(net "GND")
		)
		(pad "AC36" smd circle
			(at 10.450068 -1.89992)
			(size 0.4572 0.4572)
			(layers "F.Cu" "F.Mask" "F.Paste")
			(net "P1V25_PEX2")
		)
		(pad "AC37" smd circle
			(at 11.400028 -1.89992)
			(size 0.4572 0.4572)
			(layers "F.Cu" "F.Mask" "F.Paste")
			(net "GND")
		)
		(pad "AC38" smd circle
			(at 12.349988 -1.89992)
			(size 0.4572 0.4572)
			(layers "F.Cu" "F.Mask" "F.Paste")
			(net "P1V25_SERDES_VDDPLL_PEX2")
		)
		(pad "AC39" smd circle
			(at 13.299948 -1.89992)
			(size 0.4572 0.4572)
			(layers "F.Cu" "F.Mask" "F.Paste")
			(net "GND")
		)
		(pad "AC40" smd circle
			(at 14.249908 -1.89992)
			(size 0.4572 0.4572)
			(layers "F.Cu" "F.Mask" "F.Paste")
			(net "GND")
		)
		(pad "AC41" smd circle
			(at 15.200122 -1.89992)
			(size 0.4572 0.4572)
			(layers "F.Cu" "F.Mask" "F.Paste")
			(net "GND")
		)
		(pad "AC42" smd circle
			(at 16.150082 -1.89992)
			(size 0.4572 0.4572)
			(layers "F.Cu" "F.Mask" "F.Paste")
			(net "GND")
		)
		(pad "AC43" smd circle
			(at 17.100042 -1.89992)
			(size 0.4572 0.4572)
			(layers "F.Cu" "F.Mask" "F.Paste")
			(net "Net_1701")
		)
		(pad "AC44" smd circle
			(at 18.050002 -1.89992)
			(size 0.4572 0.4572)
			(layers "F.Cu" "F.Mask" "F.Paste")
			(net "Net_1692")
		)
		(pad "AC45" smd circle
			(at 18.999962 -1.89992)
			(size 0.4572 0.4572)
			(layers "F.Cu" "F.Mask" "F.Paste")
			(net "GND")
		)
		(pad "AC46" smd circle
			(at 19.949922 -1.89992)
			(size 0.4572 0.4572)
			(layers "F.Cu" "F.Mask" "F.Paste")
			(net "Net_1609")
		)
		(pad "AC47" smd circle
			(at 20.899882 -1.89992)
			(size 0.4572 0.4572)
			(layers "F.Cu" "F.Mask" "F.Paste")
			(net "Net_1625")
		)
		(pad "AC48" smd circle
			(at 21.850096 -1.89992)
			(size 0.4572 0.4572)
			(layers "F.Cu" "F.Mask" "F.Paste")
			(net "GND")
		)
		(pad "AC49" smd circle
			(at 22.800056 -1.89992)
			(size 0.4572 0.4572)
			(layers "F.Cu" "F.Mask" "F.Paste")
			(net "GND")
		)
		(pad "AD1" smd circle
			(at -22.800056 -0.94996)
			(size 0.4572 0.4572)
			(layers "F.Cu" "F.Mask" "F.Paste")
			(net "GND")
		)
		(pad "AD2" smd circle
			(at -21.850096 -0.94996)
			(size 0.4572 0.4572)
			(layers "F.Cu" "F.Mask" "F.Paste")
			(net "GND")
		)
		(pad "AD3" smd circle
			(at -20.899882 -0.94996)
			(size 0.4572 0.4572)
			(layers "F.Cu" "F.Mask" "F.Paste")
			(net "GND")
		)
		(pad "AD4" smd circle
			(at -19.949922 -0.94996)
			(size 0.4572 0.4572)
			(layers "F.Cu" "F.Mask" "F.Paste")
			(net "Net_382")
		)
		(pad "AD5" smd circle
			(at -18.999962 -0.94996)
			(size 0.4572 0.4572)
			(layers "F.Cu" "F.Mask" "F.Paste")
			(net "Net_383")
		)
		(pad "AD6" smd circle
			(at -18.050002 -0.94996)
			(size 0.4572 0.4572)
			(layers "F.Cu" "F.Mask" "F.Paste")
			(net "GND")
		)
		(pad "AD7" smd circle
			(at -17.100042 -0.94996)
			(size 0.4572 0.4572)
			(layers "F.Cu" "F.Mask" "F.Paste")
			(net "Net_5397")
		)
		(pad "AD8" smd circle
			(at -16.150082 -0.94996)
			(size 0.4572 0.4572)
			(layers "F.Cu" "F.Mask" "F.Paste")
			(net "Net_5399")
		)
		(pad "AD9" smd circle
			(at -15.200122 -0.94996)
			(size 0.4572 0.4572)
			(layers "F.Cu" "F.Mask" "F.Paste")
			(net "GND")
		)
		(pad "AD10" smd circle
			(at -14.249908 -0.94996)
			(size 0.4572 0.4572)
			(layers "F.Cu" "F.Mask" "F.Paste")
			(net "GND")
		)
		(pad "AD11" smd circle
			(at -13.299948 -0.94996)
			(size 0.4572 0.4572)
			(layers "F.Cu" "F.Mask" "F.Paste")
			(net "GND")
		)
		(pad "AD12" smd circle
			(at -12.349988 -0.94996)
			(size 0.4572 0.4572)
			(layers "F.Cu" "F.Mask" "F.Paste")
			(net "PCEPLL2_VDDA18_PEX2")
		)
		(pad "AD13" smd circle
			(at -11.400028 -0.94996)
			(size 0.4572 0.4572)
			(layers "F.Cu" "F.Mask" "F.Paste")
			(net "GND")
		)
		(pad "AD14" smd circle
			(at -10.450068 -0.94996)
			(size 0.4572 0.4572)
			(layers "F.Cu" "F.Mask" "F.Paste")
			(net "P0V8_PEX2")
		)
		(pad "AD15" smd circle
			(at -9.500108 -0.94996)
			(size 0.4572 0.4572)
			(layers "F.Cu" "F.Mask" "F.Paste")
			(net "GND")
		)
		(pad "AD16" smd circle
			(at -8.549894 -0.94996)
			(size 0.4572 0.4572)
			(layers "F.Cu" "F.Mask" "F.Paste")
			(net "P0V8_PEX2")
		)
		(pad "AD17" smd circle
			(at -7.599934 -0.94996)
			(size 0.4572 0.4572)
			(layers "F.Cu" "F.Mask" "F.Paste")
			(net "GND")
		)
		(pad "AD18" smd circle
			(at -6.649974 -0.94996)
			(size 0.4572 0.4572)
			(layers "F.Cu" "F.Mask" "F.Paste")
			(net "P0V8_PEX2")
		)
		(pad "AD19" smd circle
			(at -5.700014 -0.94996)
			(size 0.4572 0.4572)
			(layers "F.Cu" "F.Mask" "F.Paste")
			(net "GND")
		)
		(pad "AD20" smd circle
			(at -4.750054 -0.94996)
			(size 0.4572 0.4572)
			(layers "F.Cu" "F.Mask" "F.Paste")
			(net "P0V8_PEX2")
		)
		(pad "AD21" smd circle
			(at -3.800094 -0.94996)
			(size 0.4572 0.4572)
			(layers "F.Cu" "F.Mask" "F.Paste")
			(net "GND")
		)
		(pad "AD22" smd circle
			(at -2.84988 -0.94996)
			(size 0.4572 0.4572)
			(layers "F.Cu" "F.Mask" "F.Paste")
			(net "P0V8_PEX2")
		)
		(pad "AD23" smd circle
			(at -1.89992 -0.94996)
			(size 0.4572 0.4572)
			(layers "F.Cu" "F.Mask" "F.Paste")
			(net "GND")
		)
		(pad "AD24" smd circle
			(at -0.94996 -0.94996)
			(size 0.4572 0.4572)
			(layers "F.Cu" "F.Mask" "F.Paste")
			(net "P0V8_PEX2")
		)
		(pad "AD25" smd circle
			(at 0 -0.94996)
			(size 0.4572 0.4572)
			(layers "F.Cu" "F.Mask" "F.Paste")
			(net "GND")
		)
		(pad "AD26" smd circle
			(at 0.94996 -0.94996)
			(size 0.4572 0.4572)
			(layers "F.Cu" "F.Mask" "F.Paste")
			(net "P0V8_PEX2")
		)
		(pad "AD27" smd circle
			(at 1.89992 -0.94996)
			(size 0.4572 0.4572)
			(layers "F.Cu" "F.Mask" "F.Paste")
			(net "GND")
		)
		(pad "AD28" smd circle
			(at 2.84988 -0.94996)
			(size 0.4572 0.4572)
			(layers "F.Cu" "F.Mask" "F.Paste")
			(net "P0V8_PEX2")
		)
		(pad "AD29" smd circle
			(at 3.800094 -0.94996)
			(size 0.4572 0.4572)
			(layers "F.Cu" "F.Mask" "F.Paste")
			(net "GND")
		)
		(pad "AD30" smd circle
			(at 4.750054 -0.94996)
			(size 0.4572 0.4572)
			(layers "F.Cu" "F.Mask" "F.Paste")
			(net "P0V8_PEX2")
		)
		(pad "AD31" smd circle
			(at 5.700014 -0.94996)
			(size 0.4572 0.4572)
			(layers "F.Cu" "F.Mask" "F.Paste")
			(net "GND")
		)
		(pad "AD32" smd circle
			(at 6.649974 -0.94996)
			(size 0.4572 0.4572)
			(layers "F.Cu" "F.Mask" "F.Paste")
			(net "P0V8_SERDES_VDDA_PEX2")
		)
		(pad "AD33" smd circle
			(at 7.599934 -0.94996)
			(size 0.4572 0.4572)
			(layers "F.Cu" "F.Mask" "F.Paste")
			(net "P0V8_SERDES_VDDA_PEX2")
		)
		(pad "AD34" smd circle
			(at 8.549894 -0.94996)
			(size 0.4572 0.4572)
			(layers "F.Cu" "F.Mask" "F.Paste")
			(net "P0V8_SERDES_VDDA_PEX2")
		)
		(pad "AD35" smd circle
			(at 9.500108 -0.94996)
			(size 0.4572 0.4572)
			(layers "F.Cu" "F.Mask" "F.Paste")
			(net "GND")
		)
		(pad "AD36" smd circle
			(at 10.450068 -0.94996)
			(size 0.4572 0.4572)
			(layers "F.Cu" "F.Mask" "F.Paste")
			(net "P1V25_PEX2")
		)
		(pad "AD37" smd circle
			(at 11.400028 -0.94996)
			(size 0.4572 0.4572)
			(layers "F.Cu" "F.Mask" "F.Paste")
			(net "GND")
		)
		(pad "AD38" smd circle
			(at 12.349988 -0.94996)
			(size 0.4572 0.4572)
			(layers "F.Cu" "F.Mask" "F.Paste")
			(net "P1V25_SERDES_VDDPLL_PEX2")
		)
		(pad "AD39" smd circle
			(at 13.299948 -0.94996)
			(size 0.4572 0.4572)
			(layers "F.Cu" "F.Mask" "F.Paste")
			(net "GND")
		)
	)
)
